#ISCELL
  pure_quanta quanta_title_block_c *
  *
#ISCELL
  logical_power vcc_core *
  page38_i2
#CELL
  pure_quanta socket4677_azif0045p001c01cs *
  page38_i4
#ISCELL
  logical_power vcc_core *
  page38_i5
